(kicad_pcb
	(version 20240108)
	(generator "pcbnew")
	(generator_version "8.0")
	(general
		(thickness 1.62)
		(legacy_teardrops no)
	)
	(paper "A4")
	(title_block
		(title "Jetson Orin Baseboard")
		(date "2025-03-12")
		(rev "1.3.4")
		(company "Antmicro Ltd")
		(comment 1 "www.antmicro.com")
		(comment 9 "footprints 377-380 of 677")
	)
	(layers
		(0 "F.Cu" signal)
		(1 "In1.Cu" signal)
		(2 "In2.Cu" signal)
		(3 "In3.Cu" signal)
		(4 "In4.Cu" jumper)
		(5 "In5.Cu" signal)
		(6 "In6.Cu" signal)
		(31 "B.Cu" signal)
		(32 "B.Adhes" user "B.Adhesive")
		(33 "F.Adhes" user "F.Adhesive")
		(34 "B.Paste" user)
		(35 "F.Paste" user)
		(36 "B.SilkS" user "B.Silkscreen")
		(37 "F.SilkS" user "F.Silkscreen")
		(38 "B.Mask" user)
		(39 "F.Mask" user)
		(40 "Dwgs.User" user "User.Drawings")
		(41 "Cmts.User" user "User.Comments")
		(42 "Eco1.User" user "User.Eco1")
		(43 "Eco2.User" user "User.Eco2")
		(44 "Edge.Cuts" user)
		(45 "Margin" user)
		(46 "B.CrtYd" user "B.Courtyard")
		(47 "F.CrtYd" user "F.Courtyard")
		(48 "B.Fab" user)
		(49 "F.Fab" user)
	)
	(footprint "antmicro-footprints:R_0402_1005Metric"
		(layer "B.Cu")
		(at 102.7 75.7 180)
		(descr "Resistor SMD 0402")
		(tags "resistor SMD 0402")
		(property "Reference" "R133"
			(at -3.7 -0.45 0)
			(layer "B.SilkS")
			(effects
				(font
					(size 0.7 0.7)
					(thickness 0.15)
				)
				(justify left bottom mirror)
			)
		)
		(property "Value" "R_200R_0402"
			(at 0 -1.4 0)
			(layer "B.Fab")
			(effects
				(font
					(size 0.7 0.7)
					(thickness 0.15)
				)
				(justify left bottom mirror)
			)
		)
		(property "Footprint" "antmicro-footprints:R_0402_1005Metric"
			(at 0 0 180)
			(layer "F.Fab")
			(hide yes)
			(effects
				(font
					(size 1.27 1.27)
					(thickness 0.15)
				)
			)
		)
		(property "Datasheet" "https://www.bourns.com/docs/product-datasheets/cr.pdf"
			(at 0 0 180)
			(layer "F.Fab")
			(hide yes)
			(effects
				(font
					(size 1.27 1.27)
					(thickness 0.15)
				)
			)
		)
		(property "Author" "Antmicro"
			(at 205.4 151.4 0)
			(layer "B.Fab")
			(hide yes)
			(effects
				(font
					(size 1 1)
					(thickness 0.15)
				)
				(justify mirror)
			)
		)
		(property "License" "Apache-2.0"
			(at 205.4 151.4 0)
			(layer "B.Fab")
			(hide yes)
			(effects
				(font
					(size 1 1)
					(thickness 0.15)
				)
				(justify mirror)
			)
		)
		(property "MPN" "CR0402-FX-2000GLF"
			(at 205.4 151.4 0)
			(layer "B.Fab")
			(hide yes)
			(effects
				(font
					(size 1 1)
					(thickness 0.15)
				)
				(justify mirror)
			)
		)
		(property "Manufacturer" "Bourns"
			(at 205.4 151.4 0)
			(layer "B.Fab")
			(hide yes)
			(effects
				(font
					(size 1 1)
					(thickness 0.15)
				)
				(justify mirror)
			)
		)
		(property "Tolerance" "1%"
			(at 205.4 151.4 0)
			(layer "B.Fab")
			(hide yes)
			(effects
				(font
					(size 1 1)
					(thickness 0.15)
				)
				(justify mirror)
			)
		)
		(property "Val" "200R"
			(at 205.4 151.4 0)
			(layer "B.Fab")
			(hide yes)
			(effects
				(font
					(size 1 1)
					(thickness 0.15)
				)
				(justify mirror)
			)
		)
		(sheetname "CSI")
		(sheetfile "csi.kicad_sch")
		(attr smd)
		(fp_rect
			(start -0.925 0.47)
			(end 0.925 -0.47)
			(stroke
				(width 0.05)
				(type default)
			)
			(fill none)
			(layer "B.CrtYd")
		)
		(fp_rect
			(start -0.5 0.25)
			(end 0.5 -0.25)
			(stroke
				(width 0.15)
				(type solid)
			)
			(fill none)
			(layer "B.Fab")
		)
		(fp_text user "Author: Antmicro"
			(at -0.95 -4.169 0)
			(layer "B.Fab")
			(hide yes)
			(effects
				(font
					(size 0.7 0.7)
					(thickness 0.15)
				)
				(justify left bottom mirror)
			)
		)
		(fp_text user "License: Apache-2.0"
			(at -0.95 -5.169 0)
			(layer "B.Fab")
			(hide yes)
			(effects
				(font
					(size 0.7 0.7)
					(thickness 0.15)
				)
				(justify left bottom mirror)
			)
		)
		(fp_text user "${REFERENCE}"
			(at -0.95 -3.168 0)
			(layer "B.Fab")
			(hide yes)
			(effects
				(font
					(size 0.7 0.7)
					(thickness 0.15)
				)
				(justify left bottom mirror)
			)
		)
		(pad "1" smd roundrect
			(at -0.48 0 180)
			(size 0.59 0.64)
			(layers "B.Cu" "B.Paste" "B.Mask")
			(roundrect_rratio 0.25)
			(net 161 "Net-(D24-A)")
			(pintype "passive")
		)
		(pad "2" smd roundrect
			(at 0.48 0 180)
			(size 0.59 0.64)
			(layers "B.Cu" "B.Paste" "B.Mask")
			(roundrect_rratio 0.25)
			(net 110 "/CSI/CSIB_3V3")
			(pintype "passive")
		)
	)
	(footprint "antmicro-footprints:SOT-23-5"
		(layer "B.Cu")
		(at 59.6 83.85 90)
		(property "Reference" "U42"
			(at 2.8 1.95 0)
			(layer "B.SilkS")
			(effects
				(font
					(size 0.7 0.7)
					(thickness 0.15)
				)
				(justify left top mirror)
			)
		)
		(property "Value" "TPS7A0518P_SOT23-5"
			(at 0.002 -2.799 90)
			(layer "B.Fab")
			(effects
				(font
					(size 0.7 0.7)
					(thickness 0.15)
				)
				(justify right bottom mirror)
			)
		)
		(property "Footprint" "antmicro-footprints:SOT-23-5"
			(at 0 0 90)
			(layer "F.Fab")
			(hide yes)
			(effects
				(font
					(size 1.27 1.27)
					(thickness 0.15)
				)
			)
		)
		(property "Datasheet" "https://www.ti.com/lit/ds/symlink/tps7a05.pdf?ts=1678973651768&ref_url=https%253A%252F%252Fwww.google.com%252F"
			(at 0 0 90)
			(layer "F.Fab")
			(hide yes)
			(effects
				(font
					(size 1.27 1.27)
					(thickness 0.15)
				)
			)
		)
		(property "Author" "Antmicro"
			(at 143.45 24.25 0)
			(layer "B.Fab")
			(hide yes)
			(effects
				(font
					(size 1 1)
					(thickness 0.15)
				)
				(justify mirror)
			)
		)
		(property "License" "Apache-2.0"
			(at 143.45 24.25 0)
			(layer "B.Fab")
			(hide yes)
			(effects
				(font
					(size 1 1)
					(thickness 0.15)
				)
				(justify mirror)
			)
		)
		(property "MPN" "TPS7A0518PDBVT"
			(at 143.45 24.25 0)
			(layer "B.Fab")
			(hide yes)
			(effects
				(font
					(size 1 1)
					(thickness 0.15)
				)
				(justify mirror)
			)
		)
		(property "Manufacturer" "Texas Instruments"
			(at 143.45 24.25 0)
			(layer "B.Fab")
			(hide yes)
			(effects
				(font
					(size 1 1)
					(thickness 0.15)
				)
				(justify mirror)
			)
		)
		(sheetname "Supply")
		(sheetfile "supply.kicad_sch")
		(attr smd)
		(fp_line
			(start -0.85 -1.6)
			(end -0.55 -1.6)
			(stroke
				(width 0.15)
				(type solid)
			)
			(layer "B.SilkS")
		)
		(fp_line
			(start 0.8 -1.599)
			(end 0.8 -1.3)
			(stroke
				(width 0.15)
				(type solid)
			)
			(layer "B.SilkS")
		)
		(fp_line
			(start 0.549 -1.599)
			(end 0.8 -1.599)
			(stroke
				(width 0.15)
				(type solid)
			)
			(layer "B.SilkS")
		)
		(fp_line
			(start -0.85 -1.301)
			(end -0.85 -1.6)
			(stroke
				(width 0.15)
				(type solid)
			)
			(layer "B.SilkS")
		)
		(fp_line
			(start 0.8 0.55)
			(end 0.8 -0.55)
			(stroke
				(width 0.15)
				(type solid)
			)
			(layer "B.SilkS")
		)
		(fp_line
			(start -0.8 1.3)
			(end -0.8 1.6)
			(stroke
				(width 0.15)
				(type solid)
			)
			(layer "B.SilkS")
		)
		(fp_line
			(start 0.8 1.6)
			(end 0.8 1.3)
			(stroke
				(width 0.15)
				(type solid)
			)
			(layer "B.SilkS")
		)
		(fp_line
			(start 0.5 1.6)
			(end 0.8 1.6)
			(stroke
				(width 0.15)
				(type solid)
			)
			(layer "B.SilkS")
		)
		(fp_line
			(start -0.5 1.6)
			(end -0.8 1.6)
			(stroke
				(width 0.15)
				(type solid)
			)
			(layer "B.SilkS")
		)
		(fp_circle
			(center -1.25 1.5)
			(end -1.2 1.5)
			(stroke
				(width 0.15)
				(type solid)
			)
			(fill solid)
			(layer "B.SilkS")
		)
		(fp_rect
			(start 1.9 1.76)
			(end -1.9 -1.75)
			(stroke
				(width 0.05)
				(type solid)
			)
			(fill none)
			(layer "B.CrtYd")
		)
		(fp_line
			(start -0.874 1.05)
			(end -0.398 1.526)
			(stroke
				(width 0.15)
				(type solid)
			)
			(layer "B.Fab")
		)
		(fp_rect
			(start 0.874 -1.523)
			(end -0.873 1.525)
			(stroke
				(width 0.15)
				(type solid)
			)
			(fill none)
			(layer "B.Fab")
		)
		(fp_text user "${REFERENCE}"
			(at -1.898 -4.299 90)
			(layer "B.Fab")
			(hide yes)
			(effects
				(font
					(size 0.7 0.7)
					(thickness 0.15)
				)
				(justify right bottom mirror)
			)
		)
		(fp_text user "License: Apache-2.0"
			(at -1.898 -6.7 90)
			(layer "B.Fab")
			(hide yes)
			(effects
				(font
					(size 0.7 0.7)
					(thickness 0.15)
				)
				(justify right bottom mirror)
			)
		)
		(fp_text user "Author: Antmicro"
			(at -1.898 -5.499 90)
			(layer "B.Fab")
			(hide yes)
			(effects
				(font
					(size 0.7 0.7)
					(thickness 0.15)
				)
				(justify right bottom mirror)
			)
		)
		(pad "1" smd rect
			(at -1.351 0.951 180)
			(size 0.55 1)
			(layers "B.Cu" "B.Paste" "B.Mask")
			(net 99 "+5V")
			(pinfunction "VIN")
			(pintype "power_in")
		)
		(pad "2" smd rect
			(at -1.351 0 180)
			(size 0.55 1)
			(layers "B.Cu" "B.Paste" "B.Mask")
			(net 1 "GND")
			(pinfunction "GND")
			(pintype "power_in")
		)
		(pad "3" smd rect
			(at -1.351 -0.949 180)
			(size 0.55 1)
			(layers "B.Cu" "B.Paste" "B.Mask")
			(net 690 "Net-(U42-EN)")
			(pinfunction "EN")
			(pintype "input")
		)
		(pad "4" smd rect
			(at 1.35 -0.949 180)
			(size 0.55 1)
			(layers "B.Cu" "B.Paste" "B.Mask")
			(net 729 "unconnected-(U42-NC-Pad4)")
			(pinfunction "NC")
			(pintype "no_connect")
		)
		(pad "5" smd rect
			(at 1.35 0.951 180)
			(size 0.55 1)
			(layers "B.Cu" "B.Paste" "B.Mask")
			(net 139 "/Supply/1V8_LDO")
			(pinfunction "VOUT")
			(pintype "power_out")
		)
	)
	(footprint "antmicro-footprints:C_0402_1005Metric"
		(layer "B.Cu")
		(at 47.55 121.64 180)
		(descr "Capacitor SMD 0402")
		(tags "capacitor SMD 0402")
		(property "Reference" "C34"
			(at 6.88 1.04 0)
			(layer "B.SilkS")
			(effects
				(font
					(size 0.7 0.7)
					(thickness 0.15)
				)
				(justify left bottom mirror)
			)
		)
		(property "Value" "C_10u_0402"
			(at -1.022927 -2.155213 0)
			(layer "B.Fab")
			(effects
				(font
					(size 0.7 0.7)
					(thickness 0.15)
				)
				(justify left bottom mirror)
			)
		)
		(property "Footprint" "antmicro-footprints:C_0402_1005Metric"
			(at 0 0 180)
			(layer "F.Fab")
			(hide yes)
			(effects
				(font
					(size 1.27 1.27)
					(thickness 0.15)
				)
			)
		)
		(property "Datasheet" "https://www.yageo.com/en/Chart/Download/pdf/CC0402MRX5R5BB106"
			(at 0 0 180)
			(layer "F.Fab")
			(hide yes)
			(effects
				(font
					(size 1.27 1.27)
					(thickness 0.15)
				)
			)
		)
		(property "Author" "Antmicro"
			(at 95.1 243.28 0)
			(layer "B.Fab")
			(hide yes)
			(effects
				(font
					(size 1 1)
					(thickness 0.15)
				)
				(justify mirror)
			)
		)
		(property "Dielectric" ""
			(at 95.1 243.28 0)
			(layer "B.Fab")
			(hide yes)
			(effects
				(font
					(size 1 1)
					(thickness 0.15)
				)
				(justify mirror)
			)
		)
		(property "License" "Apache-2.0"
			(at 95.1 243.28 0)
			(layer "B.Fab")
			(hide yes)
			(effects
				(font
					(size 1 1)
					(thickness 0.15)
				)
				(justify mirror)
			)
		)
		(property "MPN" "CC0402MRX5R5BB106"
			(at 95.1 243.28 0)
			(layer "B.Fab")
			(hide yes)
			(effects
				(font
					(size 1 1)
					(thickness 0.15)
				)
				(justify mirror)
			)
		)
		(property "Manufacturer" "YAGEO"
			(at 95.1 243.28 0)
			(layer "B.Fab")
			(hide yes)
			(effects
				(font
					(size 1 1)
					(thickness 0.15)
				)
				(justify mirror)
			)
		)
		(property "Val" "10u"
			(at 95.1 243.28 0)
			(layer "B.Fab")
			(hide yes)
			(effects
				(font
					(size 1 1)
					(thickness 0.15)
				)
				(justify mirror)
			)
		)
		(property "Voltage" ""
			(at 95.1 243.28 0)
			(layer "B.Fab")
			(hide yes)
			(effects
				(font
					(size 1 1)
					(thickness 0.15)
				)
				(justify mirror)
			)
		)
		(sheetname "USB Debug, DP")
		(sheetfile "usb.kicad_sch")
		(attr smd)
		(fp_rect
			(start -0.925 0.47)
			(end 0.925 -0.47)
			(stroke
				(width 0.05)
				(type default)
			)
			(fill none)
			(layer "B.CrtYd")
		)
		(fp_line
			(start 0.504 0.25)
			(end -0.494 0.25)
			(stroke
				(width 0.15)
				(type solid)
			)
			(layer "B.Fab")
		)
		(fp_line
			(start 0.504 -0.248)
			(end 0.504 0.25)
			(stroke
				(width 0.15)
				(type solid)
			)
			(layer "B.Fab")
		)
		(fp_line
			(start -0.494 0.25)
			(end -0.494 -0.248)
			(stroke
				(width 0.15)
				(type solid)
			)
			(layer "B.Fab")
		)
		(fp_line
			(start -0.494 -0.248)
			(end 0.504 -0.248)
			(stroke
				(width 0.15)
				(type solid)
			)
			(layer "B.Fab")
		)
		(fp_text user "Author: Antmicro"
			(at -0.939 -3.399 0)
			(layer "B.Fab")
			(hide yes)
			(effects
				(font
					(size 0.7 0.7)
					(thickness 0.15)
				)
				(justify left bottom mirror)
			)
		)
		(fp_text user "${REFERENCE}"
			(at -0.939 -4.599 0)
			(layer "B.Fab")
			(hide yes)
			(effects
				(font
					(size 0.7 0.7)
					(thickness 0.15)
				)
				(justify left bottom mirror)
			)
		)
		(fp_text user "License: Apache-2.0"
			(at -0.939 -5.799 0)
			(layer "B.Fab")
			(hide yes)
			(effects
				(font
					(size 0.7 0.7)
					(thickness 0.15)
				)
				(justify left bottom mirror)
			)
		)
		(pad "1" smd roundrect
			(at -0.48 0 180)
			(size 0.59 0.64)
			(layers "B.Cu" "B.Paste" "B.Mask")
			(roundrect_rratio 0.25)
			(net 1 "GND")
			(pintype "passive")
		)
		(pad "2" smd roundrect
			(at 0.48 0 180)
			(size 0.59 0.64)
			(layers "B.Cu" "B.Paste" "B.Mask")
			(roundrect_rratio 0.25)
			(net 185 "/USB Debug, DP/FTDI_3V3")
			(pintype "passive")
		)
	)
	(footprint "antmicro-footprints:C_0402_1005Metric"
		(layer "B.Cu")
		(at 126.735 84.75)
		(descr "Capacitor SMD 0402")
		(tags "capacitor SMD 0402")
		(property "Reference" "C17"
			(at 3.015 0.45 180)
			(layer "B.SilkS")
			(effects
				(font
					(size 0.7 0.7)
					(thickness 0.15)
				)
				(justify left bottom mirror)
			)
		)
		(property "Value" "C_220n_0402"
			(at 0 -1.4 180)
			(layer "B.Fab")
			(effects
				(font
					(size 0.7 0.7)
					(thickness 0.15)
				)
				(justify left bottom mirror)
			)
		)
		(property "Footprint" "antmicro-footprints:C_0402_1005Metric"
			(at 0 0 0)
			(layer "F.Fab")
			(hide yes)
			(effects
				(font
					(size 1.27 1.27)
					(thickness 0.15)
				)
			)
		)
		(property "Datasheet" "https://www.yageo.com/en/Chart/Download/pdf/CC0402KRX5R6BB224"
			(at 0 0 0)
			(layer "F.Fab")
			(hide yes)
			(effects
				(font
					(size 1.27 1.27)
					(thickness 0.15)
				)
			)
		)
		(property "Author" "Antmicro"
			(at 0 0 0)
			(layer "B.Fab")
			(hide yes)
			(effects
				(font
					(size 1 1)
					(thickness 0.15)
				)
				(justify mirror)
			)
		)
		(property "Dielectric" ""
			(at 0 0 0)
			(layer "B.Fab")
			(hide yes)
			(effects
				(font
					(size 1 1)
					(thickness 0.15)
				)
				(justify mirror)
			)
		)
		(property "License" "Apache-2.0"
			(at 0 0 0)
			(layer "B.Fab")
			(hide yes)
			(effects
				(font
					(size 1 1)
					(thickness 0.15)
				)
				(justify mirror)
			)
		)
		(property "MPN" "CC0402KRX5R6BB224"
			(at 0 0 0)
			(layer "B.Fab")
			(hide yes)
			(effects
				(font
					(size 1 1)
					(thickness 0.15)
				)
				(justify mirror)
			)
		)
		(property "Manufacturer" "YAGEO"
			(at 0 0 0)
			(layer "B.Fab")
			(hide yes)
			(effects
				(font
					(size 1 1)
					(thickness 0.15)
				)
				(justify mirror)
			)
		)
		(property "Val" "220n"
			(at 0 0 0)
			(layer "B.Fab")
			(hide yes)
			(effects
				(font
					(size 1 1)
					(thickness 0.15)
				)
				(justify mirror)
			)
		)
		(property "Voltage" ""
			(at 0 0 0)
			(layer "B.Fab")
			(hide yes)
			(effects
				(font
					(size 1 1)
					(thickness 0.15)
				)
				(justify mirror)
			)
		)
		(sheetname "M.2")
		(sheetfile "m-2.kicad_sch")
		(attr smd)
		(fp_rect
			(start -0.925 0.47)
			(end 0.925 -0.47)
			(stroke
				(width 0.05)
				(type default)
			)
			(fill none)
			(layer "B.CrtYd")
		)
		(fp_line
			(start -0.494 -0.248)
			(end 0.504 -0.248)
			(stroke
				(width 0.15)
				(type solid)
			)
			(layer "B.Fab")
		)
		(fp_line
			(start -0.494 0.25)
			(end -0.494 -0.248)
			(stroke
				(width 0.15)
				(type solid)
			)
			(layer "B.Fab")
		)
		(fp_line
			(start 0.504 -0.248)
			(end 0.504 0.25)
			(stroke
				(width 0.15)
				(type solid)
			)
			(layer "B.Fab")
		)
		(fp_line
			(start 0.504 0.25)
			(end -0.494 0.25)
			(stroke
				(width 0.15)
				(type solid)
			)
			(layer "B.Fab")
		)
		(fp_text user "${REFERENCE}"
			(at -0.932 -3.168 180)
			(layer "B.Fab")
			(hide yes)
			(effects
				(font
					(size 0.7 0.7)
					(thickness 0.15)
				)
				(justify left bottom mirror)
			)
		)
		(fp_text user "License: Apache-2.0"
			(at -0.932 -5.17 180)
			(layer "B.Fab")
			(hide yes)
			(effects
				(font
					(size 0.7 0.7)
					(thickness 0.15)
				)
				(justify left bottom mirror)
			)
		)
		(fp_text user "Author: Antmicro"
			(at -0.932 -4.17 180)
			(layer "B.Fab")
			(hide yes)
			(effects
				(font
					(size 0.7 0.7)
					(thickness 0.15)
				)
				(justify left bottom mirror)
			)
		)
		(pad "1" smd roundrect
			(at -0.48 0)
			(size 0.59 0.64)
			(layers "B.Cu" "B.Paste" "B.Mask")
			(roundrect_rratio 0.25)
			(net 89 "/M.2/C_PCIE0_TX0_N")
			(pintype "passive")
		)
		(pad "2" smd roundrect
			(at 0.48 0)
			(size 0.59 0.64)
			(layers "B.Cu" "B.Paste" "B.Mask")
			(roundrect_rratio 0.25)
			(net 441 "PCIE0_TX0_N")
			(pintype "passive")
		)
	)
)
